FILE_TYPE = CONNECTIVITY;
{Allegro Design Entry HDL 16.5-S008 (v16-5-13Y) 10/18/2011}
"PAGE_NUMBER" = 1;
0"NC";
1"G\I";
2"P12V \G";
%"SYNONYM"
"1","(1850,2050)","0","mstr_standard","4P";
;
NEEDS_NO_SIZE"TRUE"
BODY_TYPE"PLUMBING"
CDS_LIB"mstr_standard";
"A\NWC\NAC"1;
"A\NWC\NAC"2;
%"DRAWING"
"2","(1275,1750)","0","mstr_standard","";
;
LAST_MODIFIED"Tue Oct 25 13:05:01 2011"
TITLE"P12V"
ABBREV"P12V";
END.
